(kicad_pcb
	(version 20260206)
	(generator "pcbnew")
	(generator_version "10.0")
	(general
		(thickness 1.6)
		(legacy_teardrops no)
	)
	(paper "A4")
	(title_block
		(title "Wiwynn_Tioga_Pass_MB.brd")
		(comment 1 "Tioga Pass / footprint 2167 of 4770 (J4G1), pads 1-123 of 291")
	)
	(layers
		(0 "F.Cu" signal "TOP")
		(4 "In1.Cu" signal "L2GND")
		(6 "In2.Cu" signal "L3")
		(8 "In3.Cu" signal "L4GND")
		(10 "In4.Cu" signal "L5")
		(12 "In5.Cu" signal "L6GND")
		(14 "In6.Cu" signal "L7VCC")
		(16 "In7.Cu" signal "L8VCC")
		(18 "In8.Cu" signal "L9GND")
		(20 "In9.Cu" signal "L10")
		(22 "In10.Cu" signal "L11GND")
		(24 "In11.Cu" signal "L12")
		(26 "In12.Cu" signal "L13GND")
		(2 "B.Cu" signal "BOTTOM")
		(9 "F.Adhes" user "F.Adhesive")
		(11 "B.Adhes" user "B.Adhesive")
		(13 "F.Paste" user "Package Geometry/Pastemask Top")
		(15 "B.Paste" user "Package Geometry/Pastemask Bottom")
		(5 "F.SilkS" user "Ref Des/Silkscreen Top")
		(7 "B.SilkS" user "Ref Des/Silkscreen Bottom")
		(1 "F.Mask" user "Board Geometry/Soldermask Top")
		(3 "B.Mask" user "Board Geometry/Soldermask Bottom")
		(17 "Dwgs.User" user "User.Drawings")
		(19 "Cmts.User" user "User.Comments")
		(21 "Eco1.User" user "User.Eco1")
		(23 "Eco2.User" user "User.Eco2")
		(25 "Edge.Cuts" user "Board Geometry/Outline")
		(27 "Margin" user)
		(31 "F.CrtYd" user "Package Geometry/Place Bound Top")
		(29 "B.CrtYd" user "Package Geometry/Place Bound Bottom")
		(35 "F.Fab" user "Ref Des/Assembly Top")
		(33 "B.Fab" user "Ref Des/Assembly Bottom")
	)
	(footprint ""
		(layer "F.Cu")
		(at 194.700398 -15.423642 90)
		(property "Reference" "J4G1"
			(at 9.060688 37.32911 0)
			(unlocked yes)
			(layer "F.SilkS")
			(effects
				(font
					(size 0.7874 0.5842)
					(thickness 0.1524)
				)
				(justify left)
			)
		)
		(property "Value" ""
			(at 0 0 90)
			(layer "F.Fab")
			(effects
				(font
					(size 1.27 1.27)
				)
			)
		)
		(duplicate_pad_numbers_are_jumpers no)
		(pad "" thru_hole circle
			(at 2.29997 -5.649976 90)
			(size 2.8194 2.8194)
			(drill 2.4384)
			(layers "*.Cu" "*.Mask")
			(remove_unused_layers no)
			(clearance 0.127)
			(thermal_gap 0.127)
		)
		(pad "" thru_hole oval
			(at 2.29997 68.90004 90)
			(size 2.8194 1.5748)
			(drill oval 2.4384 1.1938)
			(layers "*.Cu" "*.Mask")
			(remove_unused_layers no)
			(clearance 0.127)
			(thermal_gap 0.127)
		)
		(pad "" thru_hole circle
			(at 2.29997 132.299964 90)
			(size 2.8194 2.8194)
			(drill 2.4384)
			(layers "*.Cu" "*.Mask")
			(remove_unused_layers no)
			(clearance 0.127)
			(thermal_gap 0.127)
		)
		(pad "1" smd rect
			(at 0 0 90)
			(size 1.8034 0.508)
			(layers "F.Cu" "F.Mask" "F.Paste")
			(net "P12V_NVDIMM_ABC")
		)
		(pad "2" smd rect
			(at 0 0.849884 90)
			(size 1.8034 0.508)
			(layers "F.Cu" "F.Mask" "F.Paste")
			(net "GND")
		)
		(pad "3" smd rect
			(at 0 1.700022 90)
			(size 1.8034 0.508)
			(layers "F.Cu" "F.Mask" "F.Paste")
			(net "M_A_DQ<5>")
		)
		(pad "4" smd rect
			(at 0 2.549906 90)
			(size 1.8034 0.508)
			(layers "F.Cu" "F.Mask" "F.Paste")
			(net "GND")
		)
		(pad "5" smd rect
			(at 0 3.400044 90)
			(size 1.8034 0.508)
			(layers "F.Cu" "F.Mask" "F.Paste")
			(net "M_A_DQ<1>")
		)
		(pad "6" smd rect
			(at 0 4.249928 90)
			(size 1.8034 0.508)
			(layers "F.Cu" "F.Mask" "F.Paste")
			(net "GND")
		)
		(pad "7" smd rect
			(at 0 5.100066 90)
			(size 1.8034 0.508)
			(layers "F.Cu" "F.Mask" "F.Paste")
			(net "M_A_DQS_DP<9>")
		)
		(pad "8" smd rect
			(at 0 5.94995 90)
			(size 1.8034 0.508)
			(layers "F.Cu" "F.Mask" "F.Paste")
			(net "M_A_DQS_DN<9>")
		)
		(pad "9" smd rect
			(at 0 6.800088 90)
			(size 1.8034 0.508)
			(layers "F.Cu" "F.Mask" "F.Paste")
			(net "GND")
		)
		(pad "10" smd rect
			(at 0 7.649972 90)
			(size 1.8034 0.508)
			(layers "F.Cu" "F.Mask" "F.Paste")
			(net "M_A_DQ<7>")
		)
		(pad "11" smd rect
			(at 0 8.50011 90)
			(size 1.8034 0.508)
			(layers "F.Cu" "F.Mask" "F.Paste")
			(net "GND")
		)
		(pad "12" smd rect
			(at 0 9.349994 90)
			(size 1.8034 0.508)
			(layers "F.Cu" "F.Mask" "F.Paste")
			(net "M_A_DQ<3>")
		)
		(pad "13" smd rect
			(at 0 10.199878 90)
			(size 1.8034 0.508)
			(layers "F.Cu" "F.Mask" "F.Paste")
			(net "GND")
		)
		(pad "14" smd rect
			(at 0 11.050016 90)
			(size 1.8034 0.508)
			(layers "F.Cu" "F.Mask" "F.Paste")
			(net "M_A_DQ<13>")
		)
		(pad "15" smd rect
			(at 0 11.8999 90)
			(size 1.8034 0.508)
			(layers "F.Cu" "F.Mask" "F.Paste")
			(net "GND")
		)
		(pad "16" smd rect
			(at 0 12.750038 90)
			(size 1.8034 0.508)
			(layers "F.Cu" "F.Mask" "F.Paste")
			(net "M_A_DQ<9>")
		)
		(pad "17" smd rect
			(at 0 13.599922 90)
			(size 1.8034 0.508)
			(layers "F.Cu" "F.Mask" "F.Paste")
			(net "GND")
		)
		(pad "18" smd rect
			(at 0 14.45006 90)
			(size 1.8034 0.508)
			(layers "F.Cu" "F.Mask" "F.Paste")
			(net "M_A_DQS_DP<10>")
		)
		(pad "19" smd rect
			(at 0 15.299944 90)
			(size 1.8034 0.508)
			(layers "F.Cu" "F.Mask" "F.Paste")
			(net "M_A_DQS_DN<10>")
		)
		(pad "20" smd rect
			(at 0 16.150082 90)
			(size 1.8034 0.508)
			(layers "F.Cu" "F.Mask" "F.Paste")
			(net "GND")
		)
		(pad "21" smd rect
			(at 0 16.999966 90)
			(size 1.8034 0.508)
			(layers "F.Cu" "F.Mask" "F.Paste")
			(net "M_A_DQ<15>")
		)
		(pad "22" smd rect
			(at 0 17.850104 90)
			(size 1.8034 0.508)
			(layers "F.Cu" "F.Mask" "F.Paste")
			(net "GND")
		)
		(pad "23" smd rect
			(at 0 18.699988 90)
			(size 1.8034 0.508)
			(layers "F.Cu" "F.Mask" "F.Paste")
			(net "M_A_DQ<11>")
		)
		(pad "24" smd rect
			(at 0 19.550126 90)
			(size 1.8034 0.508)
			(layers "F.Cu" "F.Mask" "F.Paste")
			(net "GND")
		)
		(pad "25" smd rect
			(at 0 20.40001 90)
			(size 1.8034 0.508)
			(layers "F.Cu" "F.Mask" "F.Paste")
			(net "M_A_DQ<21>")
		)
		(pad "26" smd rect
			(at 0 21.249894 90)
			(size 1.8034 0.508)
			(layers "F.Cu" "F.Mask" "F.Paste")
			(net "GND")
		)
		(pad "27" smd rect
			(at 0 22.100032 90)
			(size 1.8034 0.508)
			(layers "F.Cu" "F.Mask" "F.Paste")
			(net "M_A_DQ<17>")
		)
		(pad "28" smd rect
			(at 0 22.949916 90)
			(size 1.8034 0.508)
			(layers "F.Cu" "F.Mask" "F.Paste")
			(net "GND")
		)
		(pad "29" smd rect
			(at 0 23.800054 90)
			(size 1.8034 0.508)
			(layers "F.Cu" "F.Mask" "F.Paste")
			(net "M_A_DQS_DP<11>")
		)
		(pad "30" smd rect
			(at 0 24.649938 90)
			(size 1.8034 0.508)
			(layers "F.Cu" "F.Mask" "F.Paste")
			(net "M_A_DQS_DN<11>")
		)
		(pad "31" smd rect
			(at 0 25.500076 90)
			(size 1.8034 0.508)
			(layers "F.Cu" "F.Mask" "F.Paste")
			(net "GND")
		)
		(pad "32" smd rect
			(at 0 26.34996 90)
			(size 1.8034 0.508)
			(layers "F.Cu" "F.Mask" "F.Paste")
			(net "M_A_DQ<23>")
		)
		(pad "33" smd rect
			(at 0 27.200098 90)
			(size 1.8034 0.508)
			(layers "F.Cu" "F.Mask" "F.Paste")
			(net "GND")
		)
		(pad "34" smd rect
			(at 0 28.049982 90)
			(size 1.8034 0.508)
			(layers "F.Cu" "F.Mask" "F.Paste")
			(net "M_A_DQ<19>")
		)
		(pad "35" smd rect
			(at 0 28.90012 90)
			(size 1.8034 0.508)
			(layers "F.Cu" "F.Mask" "F.Paste")
			(net "GND")
		)
		(pad "36" smd rect
			(at 0 29.750004 90)
			(size 1.8034 0.508)
			(layers "F.Cu" "F.Mask" "F.Paste")
			(net "M_A_DQ<29>")
		)
		(pad "37" smd rect
			(at 0 30.599888 90)
			(size 1.8034 0.508)
			(layers "F.Cu" "F.Mask" "F.Paste")
			(net "GND")
		)
		(pad "38" smd rect
			(at 0 31.450026 90)
			(size 1.8034 0.508)
			(layers "F.Cu" "F.Mask" "F.Paste")
			(net "M_A_DQ<25>")
		)
		(pad "39" smd rect
			(at 0 32.29991 90)
			(size 1.8034 0.508)
			(layers "F.Cu" "F.Mask" "F.Paste")
			(net "GND")
		)
		(pad "40" smd rect
			(at 0 33.150048 90)
			(size 1.8034 0.508)
			(layers "F.Cu" "F.Mask" "F.Paste")
			(net "M_A_DQS_DP<12>")
		)
		(pad "41" smd rect
			(at 0 33.999932 90)
			(size 1.8034 0.508)
			(layers "F.Cu" "F.Mask" "F.Paste")
			(net "M_A_DQS_DN<12>")
		)
		(pad "42" smd rect
			(at 0 34.85007 90)
			(size 1.8034 0.508)
			(layers "F.Cu" "F.Mask" "F.Paste")
			(net "GND")
		)
		(pad "43" smd rect
			(at 0 35.699954 90)
			(size 1.8034 0.508)
			(layers "F.Cu" "F.Mask" "F.Paste")
			(net "M_A_DQ<31>")
		)
		(pad "44" smd rect
			(at 0 36.550092 90)
			(size 1.8034 0.508)
			(layers "F.Cu" "F.Mask" "F.Paste")
			(net "GND")
		)
		(pad "45" smd rect
			(at 0 37.399976 90)
			(size 1.8034 0.508)
			(layers "F.Cu" "F.Mask" "F.Paste")
			(net "M_A_DQ<27>")
		)
		(pad "46" smd rect
			(at 0 38.250114 90)
			(size 1.8034 0.508)
			(layers "F.Cu" "F.Mask" "F.Paste")
			(net "GND")
		)
		(pad "47" smd rect
			(at 0 39.099998 90)
			(size 1.8034 0.508)
			(layers "F.Cu" "F.Mask" "F.Paste")
			(net "M_A_ECC<5>")
		)
		(pad "48" smd rect
			(at 0 39.949882 90)
			(size 1.8034 0.508)
			(layers "F.Cu" "F.Mask" "F.Paste")
			(net "GND")
		)
		(pad "49" smd rect
			(at 0 40.80002 90)
			(size 1.8034 0.508)
			(layers "F.Cu" "F.Mask" "F.Paste")
			(net "M_A_ECC<1>")
		)
		(pad "50" smd rect
			(at 0 41.649904 90)
			(size 1.8034 0.508)
			(layers "F.Cu" "F.Mask" "F.Paste")
			(net "GND")
		)
		(pad "51" smd rect
			(at 0 42.500042 90)
			(size 1.8034 0.508)
			(layers "F.Cu" "F.Mask" "F.Paste")
			(net "M_A_DQS_DP<17>")
		)
		(pad "52" smd rect
			(at 0 43.349926 90)
			(size 1.8034 0.508)
			(layers "F.Cu" "F.Mask" "F.Paste")
			(net "M_A_DQS_DN<17>")
		)
		(pad "53" smd rect
			(at 0 44.200064 90)
			(size 1.8034 0.508)
			(layers "F.Cu" "F.Mask" "F.Paste")
			(net "GND")
		)
		(pad "54" smd rect
			(at 0 45.049948 90)
			(size 1.8034 0.508)
			(layers "F.Cu" "F.Mask" "F.Paste")
			(net "M_A_ECC<7>")
		)
		(pad "55" smd rect
			(at 0 45.900086 90)
			(size 1.8034 0.508)
			(layers "F.Cu" "F.Mask" "F.Paste")
			(net "GND")
		)
		(pad "56" smd rect
			(at 0 46.74997 90)
			(size 1.8034 0.508)
			(layers "F.Cu" "F.Mask" "F.Paste")
			(net "M_A_ECC<3>")
		)
		(pad "57" smd rect
			(at 0 47.600108 90)
			(size 1.8034 0.508)
			(layers "F.Cu" "F.Mask" "F.Paste")
			(net "GND")
		)
		(pad "58" smd rect
			(at 0 48.449992 90)
			(size 1.8034 0.508)
			(layers "F.Cu" "F.Mask" "F.Paste")
			(net "M_ABC_RST_N")
		)
		(pad "59" smd rect
			(at 0 49.299876 90)
			(size 1.8034 0.508)
			(layers "F.Cu" "F.Mask" "F.Paste")
			(net "PVDDQ_ABC")
		)
		(pad "60" smd rect
			(at 0 50.150014 90)
			(size 1.8034 0.508)
			(layers "F.Cu" "F.Mask" "F.Paste")
			(net "M_A_CKE<0>")
		)
		(pad "61" smd rect
			(at 0 50.999898 90)
			(size 1.8034 0.508)
			(layers "F.Cu" "F.Mask" "F.Paste")
			(net "PVDDQ_ABC")
		)
		(pad "62" smd rect
			(at 0 51.850036 90)
			(size 1.8034 0.508)
			(layers "F.Cu" "F.Mask" "F.Paste")
			(net "M_A_ACT_N")
		)
		(pad "63" smd rect
			(at 0 52.69992 90)
			(size 1.8034 0.508)
			(layers "F.Cu" "F.Mask" "F.Paste")
			(net "M_A_BG<0>")
		)
		(pad "64" smd rect
			(at 0 53.550058 90)
			(size 1.8034 0.508)
			(layers "F.Cu" "F.Mask" "F.Paste")
			(net "PVDDQ_ABC")
		)
		(pad "65" smd rect
			(at 0 54.399942 90)
			(size 1.8034 0.508)
			(layers "F.Cu" "F.Mask" "F.Paste")
			(net "M_A_MA<12>")
		)
		(pad "66" smd rect
			(at 0 55.25008 90)
			(size 1.8034 0.508)
			(layers "F.Cu" "F.Mask" "F.Paste")
			(net "M_A_MA<9>")
		)
		(pad "67" smd rect
			(at 0 56.099964 90)
			(size 1.8034 0.508)
			(layers "F.Cu" "F.Mask" "F.Paste")
			(net "PVDDQ_ABC")
		)
		(pad "68" smd rect
			(at 0 56.950102 90)
			(size 1.8034 0.508)
			(layers "F.Cu" "F.Mask" "F.Paste")
			(net "M_A_MA<8>")
		)
		(pad "69" smd rect
			(at 0 57.799986 90)
			(size 1.8034 0.508)
			(layers "F.Cu" "F.Mask" "F.Paste")
			(net "M_A_MA<6>")
		)
		(pad "70" smd rect
			(at 0 58.650124 90)
			(size 1.8034 0.508)
			(layers "F.Cu" "F.Mask" "F.Paste")
			(net "PVDDQ_ABC")
		)
		(pad "71" smd rect
			(at 0 59.500008 90)
			(size 1.8034 0.508)
			(layers "F.Cu" "F.Mask" "F.Paste")
			(net "M_A_MA<3>")
		)
		(pad "72" smd rect
			(at 0 60.349892 90)
			(size 1.8034 0.508)
			(layers "F.Cu" "F.Mask" "F.Paste")
			(net "M_A_MA<1>")
		)
		(pad "73" smd rect
			(at 0 61.20003 90)
			(size 1.8034 0.508)
			(layers "F.Cu" "F.Mask" "F.Paste")
			(net "PVDDQ_ABC")
		)
		(pad "74" smd rect
			(at 0 62.049914 90)
			(size 1.8034 0.508)
			(layers "F.Cu" "F.Mask" "F.Paste")
			(net "M_A_CLK_DP<0>")
		)
		(pad "75" smd rect
			(at 0 62.900052 90)
			(size 1.8034 0.508)
			(layers "F.Cu" "F.Mask" "F.Paste")
			(net "M_A_CLK_DN<0>")
		)
		(pad "76" smd rect
			(at 0 63.749936 90)
			(size 1.8034 0.508)
			(layers "F.Cu" "F.Mask" "F.Paste")
			(net "PVDDQ_ABC")
		)
		(pad "77" smd rect
			(at 0 64.600074 90)
			(size 1.8034 0.508)
			(layers "F.Cu" "F.Mask" "F.Paste")
			(net "PVTT_ABC")
		)
		(pad "78" smd rect
			(at 0 70.550024 90)
			(size 1.8034 0.508)
			(layers "F.Cu" "F.Mask" "F.Paste")
			(net "FM_DIMM_EVENT_COD_N")
		)
		(pad "79" smd rect
			(at 0 71.399908 90)
			(size 1.8034 0.508)
			(layers "F.Cu" "F.Mask" "F.Paste")
			(net "M_A_MA<0>")
		)
		(pad "80" smd rect
			(at 0 72.250046 90)
			(size 1.8034 0.508)
			(layers "F.Cu" "F.Mask" "F.Paste")
			(net "PVDDQ_ABC")
		)
		(pad "81" smd rect
			(at 0 73.09993 90)
			(size 1.8034 0.508)
			(layers "F.Cu" "F.Mask" "F.Paste")
			(net "M_A_BA<0>")
		)
		(pad "82" smd rect
			(at 0 73.950068 90)
			(size 1.8034 0.508)
			(layers "F.Cu" "F.Mask" "F.Paste")
			(net "M_A_MA<16>")
		)
		(pad "83" smd rect
			(at 0 74.799952 90)
			(size 1.8034 0.508)
			(layers "F.Cu" "F.Mask" "F.Paste")
			(net "PVDDQ_ABC")
		)
		(pad "84" smd rect
			(at 0 75.65009 90)
			(size 1.8034 0.508)
			(layers "F.Cu" "F.Mask" "F.Paste")
			(net "M_A_CS_N<0>")
		)
		(pad "85" smd rect
			(at 0 76.499974 90)
			(size 1.8034 0.508)
			(layers "F.Cu" "F.Mask" "F.Paste")
			(net "PVDDQ_ABC")
		)
		(pad "86" smd rect
			(at 0 77.350112 90)
			(size 1.8034 0.508)
			(layers "F.Cu" "F.Mask" "F.Paste")
			(net "M_A_MA<15>")
		)
		(pad "87" smd rect
			(at 0 78.199996 90)
			(size 1.8034 0.508)
			(layers "F.Cu" "F.Mask" "F.Paste")
			(net "M_A_ODT<0>")
		)
		(pad "88" smd rect
			(at 0 79.04988 90)
			(size 1.8034 0.508)
			(layers "F.Cu" "F.Mask" "F.Paste")
			(net "PVDDQ_ABC")
		)
		(pad "89" smd rect
			(at 0 79.900018 90)
			(size 1.8034 0.508)
			(layers "F.Cu" "F.Mask" "F.Paste")
			(net "M_A_CS_N<1>")
		)
		(pad "90" smd rect
			(at 0 80.749902 90)
			(size 1.8034 0.508)
			(layers "F.Cu" "F.Mask" "F.Paste")
			(net "PVDDQ_ABC")
		)
		(pad "91" smd rect
			(at 0 81.60004 90)
			(size 1.8034 0.508)
			(layers "F.Cu" "F.Mask" "F.Paste")
			(net "M_A_ODT<1>")
		)
		(pad "92" smd rect
			(at 0 82.449924 90)
			(size 1.8034 0.508)
			(layers "F.Cu" "F.Mask" "F.Paste")
			(net "PVDDQ_ABC")
		)
		(pad "93" smd rect
			(at 0 83.300062 90)
			(size 1.8034 0.508)
			(layers "F.Cu" "F.Mask" "F.Paste")
			(net "M_A_CS_N<2>")
		)
		(pad "94" smd rect
			(at 0 84.149946 90)
			(size 1.8034 0.508)
			(layers "F.Cu" "F.Mask" "F.Paste")
			(net "GND")
		)
		(pad "95" smd rect
			(at 0 85.000084 90)
			(size 1.8034 0.508)
			(layers "F.Cu" "F.Mask" "F.Paste")
			(net "M_A_DQ<37>")
		)
		(pad "96" smd rect
			(at 0 85.849968 90)
			(size 1.8034 0.508)
			(layers "F.Cu" "F.Mask" "F.Paste")
			(net "GND")
		)
		(pad "97" smd rect
			(at 0 86.700106 90)
			(size 1.8034 0.508)
			(layers "F.Cu" "F.Mask" "F.Paste")
			(net "M_A_DQ<33>")
		)
		(pad "98" smd rect
			(at 0 87.54999 90)
			(size 1.8034 0.508)
			(layers "F.Cu" "F.Mask" "F.Paste")
			(net "GND")
		)
		(pad "99" smd rect
			(at 0 88.399874 90)
			(size 1.8034 0.508)
			(layers "F.Cu" "F.Mask" "F.Paste")
			(net "M_A_DQS_DP<13>")
		)
		(pad "100" smd rect
			(at 0 89.250012 90)
			(size 1.8034 0.508)
			(layers "F.Cu" "F.Mask" "F.Paste")
			(net "M_A_DQS_DN<13>")
		)
		(pad "101" smd rect
			(at 0 90.099896 90)
			(size 1.8034 0.508)
			(layers "F.Cu" "F.Mask" "F.Paste")
			(net "GND")
		)
		(pad "102" smd rect
			(at 0 90.950034 90)
			(size 1.8034 0.508)
			(layers "F.Cu" "F.Mask" "F.Paste")
			(net "M_A_DQ<39>")
		)
		(pad "103" smd rect
			(at 0 91.799918 90)
			(size 1.8034 0.508)
			(layers "F.Cu" "F.Mask" "F.Paste")
			(net "GND")
		)
		(pad "104" smd rect
			(at 0 92.650056 90)
			(size 1.8034 0.508)
			(layers "F.Cu" "F.Mask" "F.Paste")
			(net "M_A_DQ<35>")
		)
		(pad "105" smd rect
			(at 0 93.49994 90)
			(size 1.8034 0.508)
			(layers "F.Cu" "F.Mask" "F.Paste")
			(net "GND")
		)
		(pad "106" smd rect
			(at 0 94.350078 90)
			(size 1.8034 0.508)
			(layers "F.Cu" "F.Mask" "F.Paste")
			(net "M_A_DQ<45>")
		)
		(pad "107" smd rect
			(at 0 95.199962 90)
			(size 1.8034 0.508)
			(layers "F.Cu" "F.Mask" "F.Paste")
			(net "GND")
		)
		(pad "108" smd rect
			(at 0 96.0501 90)
			(size 1.8034 0.508)
			(layers "F.Cu" "F.Mask" "F.Paste")
			(net "M_A_DQ<41>")
		)
		(pad "109" smd rect
			(at 0 96.899984 90)
			(size 1.8034 0.508)
			(layers "F.Cu" "F.Mask" "F.Paste")
			(net "GND")
		)
		(pad "110" smd rect
			(at 0 97.750122 90)
			(size 1.8034 0.508)
			(layers "F.Cu" "F.Mask" "F.Paste")
			(net "M_A_DQS_DP<14>")
		)
		(pad "111" smd rect
			(at 0 98.600006 90)
			(size 1.8034 0.508)
			(layers "F.Cu" "F.Mask" "F.Paste")
			(net "M_A_DQS_DN<14>")
		)
		(pad "112" smd rect
			(at 0 99.44989 90)
			(size 1.8034 0.508)
			(layers "F.Cu" "F.Mask" "F.Paste")
			(net "GND")
		)
		(pad "113" smd rect
			(at 0 100.300028 90)
			(size 1.8034 0.508)
			(layers "F.Cu" "F.Mask" "F.Paste")
			(net "M_A_DQ<47>")
		)
		(pad "114" smd rect
			(at 0 101.149912 90)
			(size 1.8034 0.508)
			(layers "F.Cu" "F.Mask" "F.Paste")
			(net "GND")
		)
		(pad "115" smd rect
			(at 0 102.00005 90)
			(size 1.8034 0.508)
			(layers "F.Cu" "F.Mask" "F.Paste")
			(net "M_A_DQ<43>")
		)
		(pad "116" smd rect
			(at 0 102.849934 90)
			(size 1.8034 0.508)
			(layers "F.Cu" "F.Mask" "F.Paste")
			(net "GND")
		)
		(pad "117" smd rect
			(at 0 103.700072 90)
			(size 1.8034 0.508)
			(layers "F.Cu" "F.Mask" "F.Paste")
			(net "M_A_DQ<53>")
		)
		(pad "118" smd rect
			(at 0 104.549956 90)
			(size 1.8034 0.508)
			(layers "F.Cu" "F.Mask" "F.Paste")
			(net "GND")
		)
		(pad "119" smd rect
			(at 0 105.400094 90)
			(size 1.8034 0.508)
			(layers "F.Cu" "F.Mask" "F.Paste")
			(net "M_A_DQ<49>")
		)
		(pad "120" smd rect
			(at 0 106.249978 90)
			(size 1.8034 0.508)
			(layers "F.Cu" "F.Mask" "F.Paste")
			(net "GND")
		)
	)
)
